(kicad_pcb
	(version 20241229)
	(generator "pcbnew")
	(generator_version "9.0")
	(general
		(thickness 1.61)
		(legacy_teardrops no)
	)
	(paper "A3")
	(title_block
		(title "RDIMM DDR5 Tester")
		(date "2026-05-21")
		(rev "2.2.0")
		(company "Antmicro")
		(comment 9 "footprints 678-682 of 796")
	)
	(layers
		(0 "F.Cu" signal)
		(4 "In1.Cu" power)
		(6 "In2.Cu" mixed)
		(8 "In3.Cu" power)
		(10 "In4.Cu" mixed)
		(12 "In5.Cu" power)
		(14 "In6.Cu" mixed)
		(16 "In7.Cu" power)
		(18 "In8.Cu" power)
		(20 "In9.Cu" mixed)
		(22 "In10.Cu" power)
		(2 "B.Cu" signal)
		(9 "F.Adhes" user "F.Adhesive")
		(11 "B.Adhes" user "B.Adhesive")
		(13 "F.Paste" user)
		(15 "B.Paste" user)
		(5 "F.SilkS" user "F.Silkscreen")
		(7 "B.SilkS" user "B.Silkscreen")
		(1 "F.Mask" user)
		(3 "B.Mask" user)
		(17 "Dwgs.User" user "User.Drawings")
		(19 "Cmts.User" user "User.Comments")
		(21 "Eco1.User" user "User.Eco1")
		(23 "Eco2.User" user "User.Eco2")
		(25 "Edge.Cuts" user)
		(27 "Margin" user)
		(31 "F.CrtYd" user "F.Courtyard")
		(29 "B.CrtYd" user "B.Courtyard")
		(35 "F.Fab" user)
		(33 "B.Fab" user)
	)
	(footprint "antmicro-footprints:R_0402_1005Metric"
		(layer "B.Cu")
		(at 110.7 102.1 -90)
		(descr "Resistor SMD 0402")
		(tags "resistor SMD 0402")
		(property "Reference" "R41"
			(at -1.122484 0.772697 90)
			(layer "B.SilkS")
			(effects
				(font
					(size 0.7 0.7)
					(thickness 0.15)
				)
				(justify left bottom mirror)
			)
		)
		(property "Value" "R_330R_0402"
			(at -1.011843 -1.772047 90)
			(layer "B.Fab")
			(effects
				(font
					(size 0.7 0.7)
					(thickness 0.15)
				)
				(justify left bottom mirror)
			)
		)
		(property "Datasheet" "https://www.bourns.com/docs/product-datasheets/cr.pdf"
			(at 0 0 270)
			(layer "F.Fab")
			(hide yes)
			(effects
				(font
					(size 1.27 1.27)
					(thickness 0.15)
				)
			)
		)
		(property "Manufacturer" "Bourns"
			(at 0 0 270)
			(unlocked yes)
			(layer "B.Fab")
			(hide yes)
			(effects
				(font
					(size 1 1)
					(thickness 0.15)
				)
				(justify mirror)
			)
		)
		(property "MPN" "CR0402-FX-3300GLF"
			(at 0 0 270)
			(unlocked yes)
			(layer "B.Fab")
			(hide yes)
			(effects
				(font
					(size 1 1)
					(thickness 0.15)
				)
				(justify mirror)
			)
		)
		(property "Val" "330R"
			(at 0 0 270)
			(unlocked yes)
			(layer "B.Fab")
			(hide yes)
			(effects
				(font
					(size 1 1)
					(thickness 0.15)
				)
				(justify mirror)
			)
		)
		(property "License" "Apache-2.0"
			(at 0 0 270)
			(unlocked yes)
			(layer "B.Fab")
			(hide yes)
			(effects
				(font
					(size 1 1)
					(thickness 0.15)
				)
				(justify mirror)
			)
		)
		(property "Author" "Antmicro"
			(at 0 0 270)
			(unlocked yes)
			(layer "B.Fab")
			(hide yes)
			(effects
				(font
					(size 1 1)
					(thickness 0.15)
				)
				(justify mirror)
			)
		)
		(property "Tolerance" "1%"
			(at 0 0 270)
			(unlocked yes)
			(layer "B.Fab")
			(hide yes)
			(effects
				(font
					(size 1 1)
					(thickness 0.15)
				)
				(justify mirror)
			)
		)
		(sheetname "/FPGA banks HD/")
		(sheetfile "fpga-hd-banks.kicad_sch")
		(attr smd)
		(fp_rect
			(start -0.925 0.47)
			(end 0.925 -0.47)
			(stroke
				(width 0.05)
				(type default)
			)
			(fill no)
			(layer "B.CrtYd")
		)
		(fp_rect
			(start -0.5 0.25)
			(end 0.5 -0.25)
			(stroke
				(width 0.15)
				(type solid)
			)
			(fill no)
			(layer "B.Fab")
		)
		(fp_text user "${REFERENCE}"
			(at -0.95 -3.168 90)
			(layer "B.Fab")
			(effects
				(font
					(size 0.7 0.7)
					(thickness 0.15)
				)
				(justify left bottom mirror)
			)
		)
		(fp_text user "Author: Antmicro"
			(at -0.95 -4.169 90)
			(layer "B.Fab")
			(effects
				(font
					(size 0.7 0.7)
					(thickness 0.15)
				)
				(justify left bottom mirror)
			)
		)
		(fp_text user "License: Apache-2.0"
			(at -0.95 -5.169 90)
			(layer "B.Fab")
			(effects
				(font
					(size 0.7 0.7)
					(thickness 0.15)
				)
				(justify left bottom mirror)
			)
		)
		(pad "1" smd roundrect
			(at -0.48 0 270)
			(size 0.59 0.64)
			(layers "B.Cu" "B.Mask" "B.Paste")
			(roundrect_rratio 0.25)
			(net 230 "Net-(D5-A)")
			(pintype "passive")
		)
		(pad "2" smd roundrect
			(at 0.48 0 270)
			(size 0.59 0.64)
			(layers "B.Cu" "B.Mask" "B.Paste")
			(roundrect_rratio 0.25)
			(net 273 "Net-(Q5-D)")
			(pintype "passive")
		)
	)
	(footprint "antmicro-footprints:C_0603_1608Metric"
		(layer "B.Cu")
		(at 188.5 156.25 90)
		(descr "Capacitor SMD 0603")
		(tags "capacitor 0603")
		(property "Reference" "C31"
			(at 9.7 -30.8 90)
			(layer "B.SilkS")
			(effects
				(font
					(size 0.7 0.7)
					(thickness 0.15)
				)
				(justify right bottom mirror)
			)
		)
		(property "Value" "C_47u_0603"
			(at -1.42757 -1.770288 90)
			(layer "B.Fab")
			(effects
				(font
					(size 0.7 0.7)
					(thickness 0.15)
				)
				(justify right bottom mirror)
			)
		)
		(property "Datasheet" "https://www.murata.com/products/productdetail?partno=GRM188R60J476ME15%23"
			(at 0 0 90)
			(layer "F.Fab")
			(hide yes)
			(effects
				(font
					(size 1.27 1.27)
					(thickness 0.15)
				)
			)
		)
		(property "Manufacturer" "Murata"
			(at 0 0 90)
			(unlocked yes)
			(layer "B.Fab")
			(hide yes)
			(effects
				(font
					(size 1 1)
					(thickness 0.15)
				)
				(justify mirror)
			)
		)
		(property "MPN" "GRM188R60J476ME15D"
			(at 0 0 90)
			(unlocked yes)
			(layer "B.Fab")
			(hide yes)
			(effects
				(font
					(size 1 1)
					(thickness 0.15)
				)
				(justify mirror)
			)
		)
		(property "Val" "47u"
			(at 0 0 90)
			(unlocked yes)
			(layer "B.Fab")
			(hide yes)
			(effects
				(font
					(size 1 1)
					(thickness 0.15)
				)
				(justify mirror)
			)
		)
		(property "License" "Apache-2.0"
			(at 0 0 90)
			(unlocked yes)
			(layer "B.Fab")
			(hide yes)
			(effects
				(font
					(size 1 1)
					(thickness 0.15)
				)
				(justify mirror)
			)
		)
		(property "Author" "Antmicro"
			(at 0 0 90)
			(unlocked yes)
			(layer "B.Fab")
			(hide yes)
			(effects
				(font
					(size 1 1)
					(thickness 0.15)
				)
				(justify mirror)
			)
		)
		(property "Voltage" ""
			(at 0 0 90)
			(unlocked yes)
			(layer "B.Fab")
			(hide yes)
			(effects
				(font
					(size 1 1)
					(thickness 0.15)
				)
				(justify mirror)
			)
		)
		(property "Dielectric" ""
			(at 0 0 90)
			(unlocked yes)
			(layer "B.Fab")
			(hide yes)
			(effects
				(font
					(size 1 1)
					(thickness 0.15)
				)
				(justify mirror)
			)
		)
		(sheetname "/FPGA power/")
		(sheetfile "fpga-power.kicad_sch")
		(attr smd)
		(fp_line
			(start -0.15 -0.4)
			(end 0.15 -0.4)
			(stroke
				(width 0.15)
				(type solid)
			)
			(layer "B.SilkS")
		)
		(fp_line
			(start -0.15 0.4)
			(end 0.15 0.4)
			(stroke
				(width 0.15)
				(type solid)
			)
			(layer "B.SilkS")
		)
		(fp_rect
			(start -1.25 0.65)
			(end 1.25 -0.65)
			(stroke
				(width 0.05)
				(type solid)
			)
			(fill no)
			(layer "B.CrtYd")
		)
		(fp_rect
			(start -0.8 0.4)
			(end 0.8 -0.4)
			(stroke
				(width 0.15)
				(type solid)
			)
			(fill no)
			(layer "B.Fab")
		)
		(fp_text user "License: Apache-2.0"
			(at -1.682 -5.895 270)
			(layer "B.Fab")
			(effects
				(font
					(size 0.7 0.7)
					(thickness 0.15)
				)
				(justify left bottom mirror)
			)
		)
		(fp_text user "Author: Antmicro"
			(at -1.682 -4.894 270)
			(layer "B.Fab")
			(effects
				(font
					(size 0.7 0.7)
					(thickness 0.15)
				)
				(justify left bottom mirror)
			)
		)
		(fp_text user "${REFERENCE}"
			(at -1.682 -3.895 270)
			(layer "B.Fab")
			(effects
				(font
					(size 0.7 0.7)
					(thickness 0.15)
				)
				(justify left bottom mirror)
			)
		)
		(pad "1" smd roundrect
			(at -0.7 0 90)
			(size 0.8 1)
			(layers "B.Cu" "B.Mask" "B.Paste")
			(roundrect_rratio 0.2)
			(net 573 "+1V8_MGTVCCAUX")
			(pintype "passive")
		)
		(pad "2" smd roundrect
			(at 0.7 0 90)
			(size 0.8 1)
			(layers "B.Cu" "B.Mask" "B.Paste")
			(roundrect_rratio 0.2)
			(net 1 "GND")
			(pintype "passive")
		)
	)
	(footprint "antmicro-footprints:R_0402_1005Metric"
		(layer "B.Cu")
		(at 113.4 102.1 -90)
		(descr "Resistor SMD 0402")
		(tags "resistor SMD 0402")
		(property "Reference" "R40"
			(at -1.122484 0.772697 90)
			(layer "B.SilkS")
			(effects
				(font
					(size 0.7 0.7)
					(thickness 0.15)
				)
				(justify left bottom mirror)
			)
		)
		(property "Value" "R_330R_0402"
			(at -1.011843 -1.772047 90)
			(layer "B.Fab")
			(effects
				(font
					(size 0.7 0.7)
					(thickness 0.15)
				)
				(justify left bottom mirror)
			)
		)
		(property "Datasheet" "https://www.bourns.com/docs/product-datasheets/cr.pdf"
			(at 0 0 270)
			(layer "F.Fab")
			(hide yes)
			(effects
				(font
					(size 1.27 1.27)
					(thickness 0.15)
				)
			)
		)
		(property "Manufacturer" "Bourns"
			(at 0 0 270)
			(unlocked yes)
			(layer "B.Fab")
			(hide yes)
			(effects
				(font
					(size 1 1)
					(thickness 0.15)
				)
				(justify mirror)
			)
		)
		(property "MPN" "CR0402-FX-3300GLF"
			(at 0 0 270)
			(unlocked yes)
			(layer "B.Fab")
			(hide yes)
			(effects
				(font
					(size 1 1)
					(thickness 0.15)
				)
				(justify mirror)
			)
		)
		(property "Val" "330R"
			(at 0 0 270)
			(unlocked yes)
			(layer "B.Fab")
			(hide yes)
			(effects
				(font
					(size 1 1)
					(thickness 0.15)
				)
				(justify mirror)
			)
		)
		(property "License" "Apache-2.0"
			(at 0 0 270)
			(unlocked yes)
			(layer "B.Fab")
			(hide yes)
			(effects
				(font
					(size 1 1)
					(thickness 0.15)
				)
				(justify mirror)
			)
		)
		(property "Author" "Antmicro"
			(at 0 0 270)
			(unlocked yes)
			(layer "B.Fab")
			(hide yes)
			(effects
				(font
					(size 1 1)
					(thickness 0.15)
				)
				(justify mirror)
			)
		)
		(property "Tolerance" "1%"
			(at 0 0 270)
			(unlocked yes)
			(layer "B.Fab")
			(hide yes)
			(effects
				(font
					(size 1 1)
					(thickness 0.15)
				)
				(justify mirror)
			)
		)
		(sheetname "/FPGA banks HD/")
		(sheetfile "fpga-hd-banks.kicad_sch")
		(attr smd)
		(fp_rect
			(start -0.925 0.47)
			(end 0.925 -0.47)
			(stroke
				(width 0.05)
				(type default)
			)
			(fill no)
			(layer "B.CrtYd")
		)
		(fp_rect
			(start -0.5 0.25)
			(end 0.5 -0.25)
			(stroke
				(width 0.15)
				(type solid)
			)
			(fill no)
			(layer "B.Fab")
		)
		(fp_text user "License: Apache-2.0"
			(at -0.95 -5.169 90)
			(layer "B.Fab")
			(effects
				(font
					(size 0.7 0.7)
					(thickness 0.15)
				)
				(justify left bottom mirror)
			)
		)
		(fp_text user "Author: Antmicro"
			(at -0.95 -4.169 90)
			(layer "B.Fab")
			(effects
				(font
					(size 0.7 0.7)
					(thickness 0.15)
				)
				(justify left bottom mirror)
			)
		)
		(fp_text user "${REFERENCE}"
			(at -0.95 -3.168 90)
			(layer "B.Fab")
			(effects
				(font
					(size 0.7 0.7)
					(thickness 0.15)
				)
				(justify left bottom mirror)
			)
		)
		(pad "1" smd roundrect
			(at -0.48 0 270)
			(size 0.59 0.64)
			(layers "B.Cu" "B.Mask" "B.Paste")
			(roundrect_rratio 0.25)
			(net 32 "Net-(D4-A)")
			(pintype "passive")
		)
		(pad "2" smd roundrect
			(at 0.48 0 270)
			(size 0.59 0.64)
			(layers "B.Cu" "B.Mask" "B.Paste")
			(roundrect_rratio 0.25)
			(net 272 "Net-(Q4-D)")
			(pintype "passive")
		)
	)
	(footprint "antmicro-footprints:C_0402_1005Metric_EIA"
		(layer "B.Cu")
		(at 186.002 150.501999 90)
		(descr "Capacitor SMD 0402 (1005 Metric), square (rectangular) end terminal, IPC_7351 nominal, (Body size source: IPC-SM-782 page 76, https://www.pcb-3d.com/wordpress/wp-content/uploads/ipc-sm-782a_amendment_1_and_2.pdf)")
		(tags "capacitor 0402")
		(property "Reference" "C39"
			(at 9.326999 -30.627 90)
			(layer "B.SilkS")
			(effects
				(font
					(size 0.7 0.7)
					(thickness 0.15)
				)
				(justify right bottom mirror)
			)
		)
		(property "Value" "C_1u_25V_0402"
			(at 0 -1.169 90)
			(layer "B.Fab")
			(effects
				(font
					(size 0.7 0.7)
					(thickness 0.15)
				)
				(justify right bottom mirror)
			)
		)
		(property "Datasheet" "https://www.murata.com/products/productdetail?partno=GRM155R61E105KE11%23"
			(at 0 0 90)
			(layer "F.Fab")
			(hide yes)
			(effects
				(font
					(size 1.27 1.27)
					(thickness 0.15)
				)
			)
		)
		(property "MPN" "GRM155R61E105KE11J"
			(at 0 0 90)
			(unlocked yes)
			(layer "B.Fab")
			(hide yes)
			(effects
				(font
					(size 1 1)
					(thickness 0.15)
				)
				(justify mirror)
			)
		)
		(property "Manufacturer" "Murata"
			(at 0 0 90)
			(unlocked yes)
			(layer "B.Fab")
			(hide yes)
			(effects
				(font
					(size 1 1)
					(thickness 0.15)
				)
				(justify mirror)
			)
		)
		(property "License" "Apache-2.0"
			(at 0 0 90)
			(unlocked yes)
			(layer "B.Fab")
			(hide yes)
			(effects
				(font
					(size 1 1)
					(thickness 0.15)
				)
				(justify mirror)
			)
		)
		(property "Author" "Antmicro"
			(at 0 0 90)
			(unlocked yes)
			(layer "B.Fab")
			(hide yes)
			(effects
				(font
					(size 1 1)
					(thickness 0.15)
				)
				(justify mirror)
			)
		)
		(property "Val" "1u"
			(at 0 0 90)
			(unlocked yes)
			(layer "B.Fab")
			(hide yes)
			(effects
				(font
					(size 1 1)
					(thickness 0.15)
				)
				(justify mirror)
			)
		)
		(property "Voltage" "25V"
			(at 0 0 90)
			(unlocked yes)
			(layer "B.Fab")
			(hide yes)
			(effects
				(font
					(size 1 1)
					(thickness 0.15)
				)
				(justify mirror)
			)
		)
		(property "Dielectric" "X5R"
			(at 0 0 90)
			(unlocked yes)
			(layer "B.Fab")
			(hide yes)
			(effects
				(font
					(size 1 1)
					(thickness 0.15)
				)
				(justify mirror)
			)
		)
		(sheetname "/FPGA power/")
		(sheetfile "fpga-power.kicad_sch")
		(attr smd)
		(fp_rect
			(start -0.95 0.45)
			(end 0.95 -0.45)
			(stroke
				(width 0.05)
				(type default)
			)
			(fill no)
			(layer "B.CrtYd")
		)
		(fp_line
			(start 0.498 -0.248)
			(end -0.5 -0.248)
			(stroke
				(width 0.15)
				(type solid)
			)
			(layer "B.Fab")
		)
		(fp_line
			(start -0.5 -0.248)
			(end -0.5 0.25)
			(stroke
				(width 0.15)
				(type solid)
			)
			(layer "B.Fab")
		)
		(fp_line
			(start 0.498 0.25)
			(end 0.498 -0.248)
			(stroke
				(width 0.15)
				(type solid)
			)
			(layer "B.Fab")
		)
		(fp_line
			(start -0.5 0.25)
			(end 0.498 0.25)
			(stroke
				(width 0.15)
				(type solid)
			)
			(layer "B.Fab")
		)
		(fp_text user "License: Apache-2.0"
			(at -0.9656 -4.369 270)
			(layer "B.Fab")
			(effects
				(font
					(size 0.7 0.7)
					(thickness 0.15)
				)
				(justify left bottom mirror)
			)
		)
		(fp_text user "${REFERENCE}"
			(at -0.9656 -3.169 270)
			(layer "B.Fab")
			(effects
				(font
					(size 0.7 0.7)
					(thickness 0.15)
				)
				(justify left bottom mirror)
			)
		)
		(fp_text user "Author: Antmicro"
			(at -0.9656 -5.569 270)
			(layer "B.Fab")
			(effects
				(font
					(size 0.7 0.7)
					(thickness 0.15)
				)
				(justify left bottom mirror)
			)
		)
		(pad "1" smd roundrect
			(at -0.5 0)
			(size 0.6 0.6)
			(layers "B.Cu" "B.Mask" "B.Paste")
			(roundrect_rratio 0.25)
			(net 1 "GND")
			(pintype "passive")
		)
		(pad "2" smd roundrect
			(at 0.498 0 90)
			(size 0.6 0.6)
			(layers "B.Cu" "B.Mask" "B.Paste")
			(roundrect_rratio 0.25)
			(net 553 "+0V85")
			(pintype "passive")
		)
	)
	(footprint "antmicro-footprints:C_0603_1608Metric"
		(layer "B.Cu")
		(at 188.5 148.3 -90)
		(descr "Capacitor SMD 0603")
		(tags "capacitor 0603")
		(property "Reference" "C11"
			(at -11.925 30.7 90)
			(layer "B.SilkS")
			(effects
				(font
					(size 0.7 0.7)
					(thickness 0.15)
				)
				(justify left bottom mirror)
			)
		)
		(property "Value" "C_47u_0603"
			(at -1.42757 -1.770288 90)
			(layer "B.Fab")
			(effects
				(font
					(size 0.7 0.7)
					(thickness 0.15)
				)
				(justify left bottom mirror)
			)
		)
		(property "Datasheet" "https://www.murata.com/products/productdetail?partno=GRM188R60J476ME15%23"
			(at 0 0 270)
			(layer "F.Fab")
			(hide yes)
			(effects
				(font
					(size 1.27 1.27)
					(thickness 0.15)
				)
			)
		)
		(property "Manufacturer" "Murata"
			(at 0 0 270)
			(unlocked yes)
			(layer "B.Fab")
			(hide yes)
			(effects
				(font
					(size 1 1)
					(thickness 0.15)
				)
				(justify mirror)
			)
		)
		(property "MPN" "GRM188R60J476ME15D"
			(at 0 0 270)
			(unlocked yes)
			(layer "B.Fab")
			(hide yes)
			(effects
				(font
					(size 1 1)
					(thickness 0.15)
				)
				(justify mirror)
			)
		)
		(property "Val" "47u"
			(at 0 0 270)
			(unlocked yes)
			(layer "B.Fab")
			(hide yes)
			(effects
				(font
					(size 1 1)
					(thickness 0.15)
				)
				(justify mirror)
			)
		)
		(property "License" "Apache-2.0"
			(at 0 0 270)
			(unlocked yes)
			(layer "B.Fab")
			(hide yes)
			(effects
				(font
					(size 1 1)
					(thickness 0.15)
				)
				(justify mirror)
			)
		)
		(property "Author" "Antmicro"
			(at 0 0 270)
			(unlocked yes)
			(layer "B.Fab")
			(hide yes)
			(effects
				(font
					(size 1 1)
					(thickness 0.15)
				)
				(justify mirror)
			)
		)
		(property "Voltage" ""
			(at 0 0 270)
			(unlocked yes)
			(layer "B.Fab")
			(hide yes)
			(effects
				(font
					(size 1 1)
					(thickness 0.15)
				)
				(justify mirror)
			)
		)
		(property "Dielectric" ""
			(at 0 0 270)
			(unlocked yes)
			(layer "B.Fab")
			(hide yes)
			(effects
				(font
					(size 1 1)
					(thickness 0.15)
				)
				(justify mirror)
			)
		)
		(sheetname "/FPGA power/")
		(sheetfile "fpga-power.kicad_sch")
		(attr smd)
		(fp_line
			(start -0.15 0.4)
			(end 0.15 0.4)
			(stroke
				(width 0.15)
				(type solid)
			)
			(layer "B.SilkS")
		)
		(fp_line
			(start -0.15 -0.4)
			(end 0.15 -0.4)
			(stroke
				(width 0.15)
				(type solid)
			)
			(layer "B.SilkS")
		)
		(fp_rect
			(start -1.25 0.65)
			(end 1.25 -0.65)
			(stroke
				(width 0.05)
				(type solid)
			)
			(fill no)
			(layer "B.CrtYd")
		)
		(fp_rect
			(start -0.8 0.4)
			(end 0.8 -0.4)
			(stroke
				(width 0.15)
				(type solid)
			)
			(fill no)
			(layer "B.Fab")
		)
		(fp_text user "License: Apache-2.0"
			(at -1.682 -5.895 90)
			(layer "B.Fab")
			(effects
				(font
					(size 0.7 0.7)
					(thickness 0.15)
				)
				(justify left bottom mirror)
			)
		)
		(fp_text user "${REFERENCE}"
			(at -1.682 -3.895 90)
			(layer "B.Fab")
			(effects
				(font
					(size 0.7 0.7)
					(thickness 0.15)
				)
				(justify left bottom mirror)
			)
		)
		(fp_text user "Author: Antmicro"
			(at -1.682 -4.894 90)
			(layer "B.Fab")
			(effects
				(font
					(size 0.7 0.7)
					(thickness 0.15)
				)
				(justify left bottom mirror)
			)
		)
		(pad "1" smd roundrect
			(at -0.7 0 270)
			(size 0.8 1)
			(layers "B.Cu" "B.Mask" "B.Paste")
			(roundrect_rratio 0.2)
			(net 797 "+1V8")
			(pintype "passive")
		)
		(pad "2" smd roundrect
			(at 0.7 0 270)
			(size 0.8 1)
			(layers "B.Cu" "B.Mask" "B.Paste")
			(roundrect_rratio 0.2)
			(net 1 "GND")
			(pintype "passive")
		)
	)
)
